# T6G (Grand Teton) — schematic netlist excerpt (pin names and nets, part order shuffled) for the footprints in the layout excerpt that follows; sources: Cadence DE-HDL packaged netlist, KiCad conversion of 04192023_DAF0TMB3IC0_F0TG_MB_C_brd_V02_OCP.brd

C868  Q_CAP_DIFFBUS  DIFF BUS_0.22UF 6.3V 20% X6S  pkg C0201  page 64 : \1\ = P5E_CPU0_P2_TX_C_DN<0> ; \2\ = P5E_CPU0_P2_TX_DN<0>
C950  Q_CAP_DIFFBUS  DIFF BUS_0.22UF 6.3V 20% X6S  pkg C0201  page 63 : \1\ = P5E_CPU0_P1_TX_C_DN<7> ; \2\ = P5E_CPU0_P1_TX_DN<7>
D5  Q_LED  IC  pkg SMLF  page 166 : A = PU_BOOT_RDY_LED ; C = BOOT_RDY_LED_N
TP9  TP  NA  pkg TP  page 27 : TP = VSENSE_PVDD18_S5_P0_DP

(kicad_pcb
	(version 20260206)
	(generator "pcbnew")
	(generator_version "10.0")
	(general
		(thickness 1.6)
		(legacy_teardrops no)
	)
	(paper "A4")
	(title_block
		(title "04192023_DAF0TMB3IC0_F0TG_MB_C_brd_V02_OCP.brd")
		(comment 1 "Grand Teton / footprints 202-205 of 8354")
	)
	(layers
		(0 "F.Cu" signal "TOP")
		(4 "In1.Cu" signal "GND")
		(6 "In2.Cu" signal "IN1")
		(8 "In3.Cu" signal "GND1")
		(10 "In4.Cu" signal "IN2")
		(12 "In5.Cu" signal "GND2")
		(14 "In6.Cu" signal "IN3")
		(16 "In7.Cu" signal "GND3")
		(18 "In8.Cu" signal "VCC")
		(20 "In9.Cu" signal "VCC1")
		(22 "In10.Cu" signal "GND4")
		(24 "In11.Cu" signal "IN4")
		(26 "In12.Cu" signal "GND5")
		(28 "In13.Cu" signal "IN5")
		(30 "In14.Cu" signal "GND6")
		(32 "In15.Cu" signal "IN6")
		(34 "In16.Cu" signal "GND7")
		(2 "B.Cu" signal "BOTTOM")
		(9 "F.Adhes" user "F.Adhesive")
		(11 "B.Adhes" user "B.Adhesive")
		(13 "F.Paste" user "Package Geometry/Pastemask Top")
		(15 "B.Paste" user "Package Geometry/Pastemask Bottom")
		(5 "F.SilkS" user "Ref Des/Silkscreen Top")
		(7 "B.SilkS" user "Ref Des/Silkscreen Bottom")
		(1 "F.Mask" user "Board Geometry/Soldermask Top")
		(3 "B.Mask" user "Board Geometry/Soldermask Bottom")
		(17 "Dwgs.User" user "User.Drawings")
		(19 "Cmts.User" user "User.Comments")
		(21 "Eco1.User" user "User.Eco1")
		(23 "Eco2.User" user "User.Eco2")
		(25 "Edge.Cuts" user "Board Geometry/Outline")
		(27 "Margin" user)
		(31 "F.CrtYd" user "Package Geometry/Place Bound Top")
		(29 "B.CrtYd" user "Package Geometry/Place Bound Bottom")
		(35 "F.Fab" user "Ref Des/Assembly Top")
		(33 "B.Fab" user "Ref Des/Assembly Bottom")
	)
	(footprint ""
		(layer "F.Cu")
		(at 339.70976 -15.924276 90)
		(property "Reference" "D5"
			(at -2.9718 -0.079248 90)
			(unlocked yes)
			(layer "F.SilkS")
			(effects
				(font
					(size 0.7874 0.5842)
					(thickness 0.1524)
				)
				(justify left)
			)
		)
		(property "Value" ""
			(at 0 0 90)
			(layer "F.Fab")
			(effects
				(font
					(size 1.27 1.27)
				)
			)
		)
		(duplicate_pad_numbers_are_jumpers no)
		(fp_line
			(start 1.16078 -0.4826)
			(end 1.16078 0.4826)
			(stroke
				(width 0.1524)
				(type default)
			)
			(layer "F.SilkS")
		)
		(fp_line
			(start 1.03378 -0.4826)
			(end 1.03378 0.4826)
			(stroke
				(width 0.1524)
				(type default)
			)
			(layer "F.SilkS")
		)
		(fp_line
			(start 0.90678 -0.4826)
			(end 0.90678 0.4826)
			(stroke
				(width 0.1524)
				(type default)
			)
			(layer "F.SilkS")
		)
		(fp_line
			(start -0.64008 -0.4826)
			(end 1.16078 -0.4826)
			(stroke
				(width 0.1524)
				(type default)
			)
			(layer "F.SilkS")
		)
		(fp_line
			(start -0.79248 -0.4826)
			(end 1.03378 -0.4826)
			(stroke
				(width 0.1524)
				(type default)
			)
			(layer "F.SilkS")
		)
		(fp_line
			(start -0.89408 -0.4826)
			(end 0.90678 -0.4826)
			(stroke
				(width 0.1524)
				(type default)
			)
			(layer "F.SilkS")
		)
		(fp_line
			(start 1.16078 0.4826)
			(end -0.64008 0.4826)
			(stroke
				(width 0.1524)
				(type default)
			)
			(layer "F.SilkS")
		)
		(fp_line
			(start 1.03378 0.4826)
			(end -0.79248 0.4826)
			(stroke
				(width 0.1524)
				(type default)
			)
			(layer "F.SilkS")
		)
		(fp_line
			(start 0.90678 0.4826)
			(end -0.90678 0.4826)
			(stroke
				(width 0.1524)
				(type default)
			)
			(layer "F.SilkS")
		)
		(fp_line
			(start -0.90678 0.4826)
			(end -0.90678 -0.4699)
			(stroke
				(width 0.1524)
				(type default)
			)
			(layer "F.SilkS")
		)
		(fp_line
			(start 0.499872 -0.249936)
			(end 0.499872 0.249936)
			(stroke
				(width 0.1)
				(type default)
			)
			(layer "F.Fab")
		)
		(fp_line
			(start -0.499872 -0.249936)
			(end 0.499872 -0.249936)
			(stroke
				(width 0.1)
				(type default)
			)
			(layer "F.Fab")
		)
		(fp_line
			(start 0.499872 0.249936)
			(end -0.499872 0.249936)
			(stroke
				(width 0.1)
				(type default)
			)
			(layer "F.Fab")
		)
		(fp_line
			(start -0.499872 0.249936)
			(end -0.499872 -0.249936)
			(stroke
				(width 0.1)
				(type default)
			)
			(layer "F.Fab")
		)
		(pad "A" smd rect
			(at -0.47498 0 90)
			(size 0.6096 0.7112)
			(layers "F.Cu" "F.Mask" "F.Paste")
			(net "PU_BOOT_RDY_LED")
		)
		(pad "C" smd rect
			(at 0.47498 0 90)
			(size 0.6096 0.7112)
			(layers "F.Cu" "F.Mask" "F.Paste")
			(net "BOOT_RDY_LED_N")
		)
	)
	(footprint ""
		(layer "F.Cu")
		(at 303.69383 -153.917142 180)
		(property "Reference" "TP9"
			(at 2.88544 -0.005334 0)
			(unlocked yes)
			(layer "F.SilkS")
			(effects
				(font
					(size 0.7874 0.5842)
					(thickness 0.1524)
				)
				(justify left)
			)
		)
		(property "Value" ""
			(at 0 0 180)
			(layer "F.Fab")
			(effects
				(font
					(size 1.27 1.27)
				)
			)
		)
		(duplicate_pad_numbers_are_jumpers no)
		(pad "1" smd circle
			(at 0 0 180)
			(size 0.762 0.762)
			(layers "F.Cu" "F.Mask" "F.Paste")
			(net "VSENSE_PVDD18_S5_P0_DP")
		)
	)
	(footprint ""
		(layer "F.Cu")
		(at 344.344244 -383.88163 -90)
		(property "Reference" "C950"
			(at 0 0 270)
			(layer "F.SilkS")
			(hide yes)
			(effects
				(font
					(size 1.27 1.27)
				)
			)
		)
		(property "Value" ""
			(at 0 0 270)
			(layer "F.Fab")
			(effects
				(font
					(size 1.27 1.27)
				)
			)
		)
		(duplicate_pad_numbers_are_jumpers no)
		(fp_line
			(start -0.299974 0.150114)
			(end -0.299974 -0.150114)
			(stroke
				(width 0.1)
				(type default)
			)
			(layer "F.Fab")
		)
		(fp_line
			(start 0.299974 0.150114)
			(end -0.299974 0.150114)
			(stroke
				(width 0.1)
				(type default)
			)
			(layer "F.Fab")
		)
		(fp_line
			(start -0.299974 -0.150114)
			(end 0.299974 -0.150114)
			(stroke
				(width 0.1)
				(type default)
			)
			(layer "F.Fab")
		)
		(fp_line
			(start 0.299974 -0.150114)
			(end 0.299974 0.150114)
			(stroke
				(width 0.1)
				(type default)
			)
			(layer "F.Fab")
		)
		(pad "1" smd rect
			(at -0.2667 0 270)
			(size 0.3048 0.381)
			(layers "F.Cu" "F.Mask" "F.Paste")
			(net "P5E_CPU0_P1_TX_C_DN<7>")
		)
		(pad "2" smd rect
			(at 0.2667 0 270)
			(size 0.3048 0.381)
			(layers "F.Cu" "F.Mask" "F.Paste")
			(net "P5E_CPU0_P1_TX_DN<7>")
		)
	)
	(footprint ""
		(layer "F.Cu")
		(at 398.595088 -389.86206 180)
		(property "Reference" "C868"
			(at 0 0 180)
			(layer "F.SilkS")
			(hide yes)
			(effects
				(font
					(size 1.27 1.27)
				)
			)
		)
		(property "Value" ""
			(at 0 0 180)
			(layer "F.Fab")
			(effects
				(font
					(size 1.27 1.27)
				)
			)
		)
		(duplicate_pad_numbers_are_jumpers no)
		(fp_line
			(start 0.299974 0.150114)
			(end -0.299974 0.150114)
			(stroke
				(width 0.1)
				(type default)
			)
			(layer "F.Fab")
		)
		(fp_line
			(start 0.299974 -0.150114)
			(end 0.299974 0.150114)
			(stroke
				(width 0.1)
				(type default)
			)
			(layer "F.Fab")
		)
		(fp_line
			(start -0.299974 0.150114)
			(end -0.299974 -0.150114)
			(stroke
				(width 0.1)
				(type default)
			)
			(layer "F.Fab")
		)
		(fp_line
			(start -0.299974 -0.150114)
			(end 0.299974 -0.150114)
			(stroke
				(width 0.1)
				(type default)
			)
			(layer "F.Fab")
		)
		(pad "1" smd rect
			(at -0.2667 0 180)
			(size 0.3048 0.381)
			(layers "F.Cu" "F.Mask" "F.Paste")
			(net "P5E_CPU0_P2_TX_C_DN<0>")
		)
		(pad "2" smd rect
			(at 0.2667 0 180)
			(size 0.3048 0.381)
			(layers "F.Cu" "F.Mask" "F.Paste")
			(net "P5E_CPU0_P2_TX_DN<0>")
		)
	)
)
